FILE_TYPE = CONNECTIVITY;
{Allegro Design Entry HDL 17.4-2019 S026 (4007227) 1/17/2022}
"PAGE_NUMBER" = 444;
0"NC";
END.
